(kicad_pcb
	(version 20260206)
	(generator "pcbnew")
	(generator_version "10.0")
	(general
		(thickness 1.6)
		(legacy_teardrops no)
	)
	(paper "A4")
	(title_block
		(title "03242023_DA0F0TMBIJ0_F0T_Motherboard_J_brd_V01_OCP.brd")
		(comment 1 "Grand Teton / footprints 242-244 of 6105")
	)
	(layers
		(0 "F.Cu" signal "TOP")
		(4 "In1.Cu" signal "GND")
		(6 "In2.Cu" signal "IN1")
		(8 "In3.Cu" signal "GND1")
		(10 "In4.Cu" signal "IN2")
		(12 "In5.Cu" signal "GND2")
		(14 "In6.Cu" signal "IN3")
		(16 "In7.Cu" signal "GND3")
		(18 "In8.Cu" signal "VCC")
		(20 "In9.Cu" signal "VCC1")
		(22 "In10.Cu" signal "GND4")
		(24 "In11.Cu" signal "IN4")
		(26 "In12.Cu" signal "GND5")
		(28 "In13.Cu" signal "IN5")
		(30 "In14.Cu" signal "GND6")
		(32 "In15.Cu" signal "IN6")
		(34 "In16.Cu" signal "GND7")
		(2 "B.Cu" signal "BOTTOM")
		(9 "F.Adhes" user "F.Adhesive")
		(11 "B.Adhes" user "B.Adhesive")
		(13 "F.Paste" user "Package Geometry/Pastemask Top")
		(15 "B.Paste" user "Package Geometry/Pastemask Bottom")
		(5 "F.SilkS" user "Ref Des/Silkscreen Top")
		(7 "B.SilkS" user "Ref Des/Silkscreen Bottom")
		(1 "F.Mask" user "Board Geometry/Soldermask Top")
		(3 "B.Mask" user "Board Geometry/Soldermask Bottom")
		(17 "Dwgs.User" user "User.Drawings")
		(19 "Cmts.User" user "User.Comments")
		(21 "Eco1.User" user "User.Eco1")
		(23 "Eco2.User" user "User.Eco2")
		(25 "Edge.Cuts" user "Board Geometry/Outline")
		(27 "Margin" user)
		(31 "F.CrtYd" user "Package Geometry/Place Bound Top")
		(29 "B.CrtYd" user "Package Geometry/Place Bound Bottom")
		(35 "F.Fab" user "Ref Des/Assembly Top")
		(33 "B.Fab" user "Ref Des/Assembly Bottom")
	)
	(footprint ""
		(layer "F.Cu")
		(at 116.561616 -241.97691 -90)
		(property "Reference" "C286"
			(at 0 0 270)
			(layer "F.SilkS")
			(hide yes)
			(effects
				(font
					(size 1.27 1.27)
				)
			)
		)
		(property "Value" ""
			(at 0 0 270)
			(layer "F.Fab")
			(effects
				(font
					(size 1.27 1.27)
				)
			)
		)
		(duplicate_pad_numbers_are_jumpers no)
		(fp_line
			(start -0.7874 0.4064)
			(end -0.7874 -0.4064)
			(stroke
				(width 0.1524)
				(type default)
			)
			(layer "F.SilkS")
		)
		(fp_line
			(start 0.7874 0.4064)
			(end -0.7874 0.4064)
			(stroke
				(width 0.1524)
				(type default)
			)
			(layer "F.SilkS")
		)
		(fp_line
			(start -0.7874 -0.4064)
			(end 0.7874 -0.4064)
			(stroke
				(width 0.1524)
				(type default)
			)
			(layer "F.SilkS")
		)
		(fp_line
			(start 0.7874 -0.4064)
			(end 0.7874 0.4064)
			(stroke
				(width 0.1524)
				(type default)
			)
			(layer "F.SilkS")
		)
		(fp_line
			(start -0.67945 0.3048)
			(end -0.67945 -0.305054)
			(stroke
				(width 0.1)
				(type default)
			)
			(layer "F.Fab")
		)
		(fp_line
			(start -0.12065 0.3048)
			(end -0.67945 0.3048)
			(stroke
				(width 0.1)
				(type default)
			)
			(layer "F.Fab")
		)
		(fp_line
			(start 0.120396 0.3048)
			(end 0.120396 0.2794)
			(stroke
				(width 0.1)
				(type default)
			)
			(layer "F.Fab")
		)
		(fp_line
			(start 0.67945 0.3048)
			(end 0.120396 0.3048)
			(stroke
				(width 0.1)
				(type default)
			)
			(layer "F.Fab")
		)
		(fp_line
			(start -0.12065 0.2794)
			(end -0.12065 0.3048)
			(stroke
				(width 0.1)
				(type default)
			)
			(layer "F.Fab")
		)
		(fp_line
			(start 0.120396 0.2794)
			(end -0.12065 0.2794)
			(stroke
				(width 0.1)
				(type default)
			)
			(layer "F.Fab")
		)
		(fp_line
			(start -0.12065 -0.2794)
			(end 0.12065 -0.2794)
			(stroke
				(width 0.1)
				(type default)
			)
			(layer "F.Fab")
		)
		(fp_line
			(start 0.12065 -0.2794)
			(end 0.12065 -0.3048)
			(stroke
				(width 0.1)
				(type default)
			)
			(layer "F.Fab")
		)
		(fp_line
			(start 0.12065 -0.3048)
			(end 0.67945 -0.3048)
			(stroke
				(width 0.1)
				(type default)
			)
			(layer "F.Fab")
		)
		(fp_line
			(start 0.67945 -0.3048)
			(end 0.67945 0.3048)
			(stroke
				(width 0.1)
				(type default)
			)
			(layer "F.Fab")
		)
		(fp_line
			(start -0.67945 -0.305054)
			(end -0.12065 -0.305054)
			(stroke
				(width 0.1)
				(type default)
			)
			(layer "F.Fab")
		)
		(fp_line
			(start -0.12065 -0.305054)
			(end -0.12065 -0.2794)
			(stroke
				(width 0.1)
				(type default)
			)
			(layer "F.Fab")
		)
		(pad "1" smd circle
			(at -0.40005 0 270)
			(size 0 0)
			(layers "F.Cu" "F.Mask" "F.Paste")
			(net "PVCCIN_CPU1")
		)
		(pad "2" smd circle
			(at 0.40005 0 270)
			(size 0 0)
			(layers "F.Cu" "F.Mask" "F.Paste")
			(net "GND")
		)
	)
	(footprint ""
		(layer "F.Cu")
		(at 157.28188 -108.295948 180)
		(property "Reference" "R2071"
			(at 0 0 180)
			(layer "F.SilkS")
			(hide yes)
			(effects
				(font
					(size 1.27 1.27)
				)
			)
		)
		(property "Value" ""
			(at 0 0 180)
			(layer "F.Fab")
			(effects
				(font
					(size 1.27 1.27)
				)
			)
		)
		(duplicate_pad_numbers_are_jumpers no)
		(fp_line
			(start 0.7874 0.4064)
			(end -0.7874 0.4064)
			(stroke
				(width 0.1524)
				(type default)
			)
			(layer "F.SilkS")
		)
		(fp_line
			(start 0.7874 -0.4064)
			(end 0.7874 0.4064)
			(stroke
				(width 0.1524)
				(type default)
			)
			(layer "F.SilkS")
		)
		(fp_line
			(start -0.7874 0.4064)
			(end -0.7874 -0.4064)
			(stroke
				(width 0.1524)
				(type default)
			)
			(layer "F.SilkS")
		)
		(fp_line
			(start -0.7874 -0.4064)
			(end 0.7874 -0.4064)
			(stroke
				(width 0.1524)
				(type default)
			)
			(layer "F.SilkS")
		)
		(fp_line
			(start 0.67945 0.3048)
			(end 0.120396 0.3048)
			(stroke
				(width 0.1)
				(type default)
			)
			(layer "F.Fab")
		)
		(fp_line
			(start 0.67945 -0.3048)
			(end 0.67945 0.3048)
			(stroke
				(width 0.1)
				(type default)
			)
			(layer "F.Fab")
		)
		(fp_line
			(start 0.12065 -0.2794)
			(end 0.12065 -0.3048)
			(stroke
				(width 0.1)
				(type default)
			)
			(layer "F.Fab")
		)
		(fp_line
			(start 0.12065 -0.3048)
			(end 0.67945 -0.3048)
			(stroke
				(width 0.1)
				(type default)
			)
			(layer "F.Fab")
		)
		(fp_line
			(start 0.120396 0.3048)
			(end 0.120396 0.2794)
			(stroke
				(width 0.1)
				(type default)
			)
			(layer "F.Fab")
		)
		(fp_line
			(start 0.120396 0.2794)
			(end -0.12065 0.2794)
			(stroke
				(width 0.1)
				(type default)
			)
			(layer "F.Fab")
		)
		(fp_line
			(start -0.12065 0.3048)
			(end -0.67945 0.3048)
			(stroke
				(width 0.1)
				(type default)
			)
			(layer "F.Fab")
		)
		(fp_line
			(start -0.12065 0.2794)
			(end -0.12065 0.3048)
			(stroke
				(width 0.1)
				(type default)
			)
			(layer "F.Fab")
		)
		(fp_line
			(start -0.12065 -0.2794)
			(end 0.12065 -0.2794)
			(stroke
				(width 0.1)
				(type default)
			)
			(layer "F.Fab")
		)
		(fp_line
			(start -0.12065 -0.305054)
			(end -0.12065 -0.2794)
			(stroke
				(width 0.1)
				(type default)
			)
			(layer "F.Fab")
		)
		(fp_line
			(start -0.67945 0.3048)
			(end -0.67945 -0.305054)
			(stroke
				(width 0.1)
				(type default)
			)
			(layer "F.Fab")
		)
		(fp_line
			(start -0.67945 -0.305054)
			(end -0.12065 -0.305054)
			(stroke
				(width 0.1)
				(type default)
			)
			(layer "F.Fab")
		)
		(pad "1" smd circle
			(at -0.40005 0 180)
			(size 0 0)
			(layers "F.Cu" "F.Mask" "F.Paste")
			(net "FM_BMC_SUSACK_R_N")
		)
		(pad "2" smd circle
			(at 0.40005 0 180)
			(size 0 0)
			(layers "F.Cu" "F.Mask" "F.Paste")
			(net "FM_SUSACK_N")
		)
	)
	(footprint ""
		(layer "F.Cu")
		(at 6.999986 -22.29993)
		(property "Reference" "H100"
			(at -4.17322 -5.964428 0)
			(unlocked yes)
			(layer "F.SilkS")
			(effects
				(font
					(size 0.7874 0.5842)
					(thickness 0.1524)
				)
				(justify left)
			)
		)
		(property "Value" ""
			(at 0 0 0)
			(layer "F.Fab")
			(effects
				(font
					(size 1.27 1.27)
				)
			)
		)
		(duplicate_pad_numbers_are_jumpers no)
		(pad "1" thru_hole circle
			(at 0 0)
			(size 10.0076 10.0076)
			(drill 5.6134)
			(layers "*.Cu" "*.Mask")
			(remove_unused_layers no)
			(net "GND")
			(clearance -1.9431)
		)
	)
)
